(kicad_pcb
	(version 20260206)
	(generator "pcbnew")
	(generator_version "10.0")
	(general
		(thickness 1.6)
		(legacy_teardrops no)
	)
	(paper "A4")
	(title_block
		(title "04192023_DAF0TMB3IC0_F0TG_MB_C_brd_V02_OCP.brd")
		(comment 1 "Grand Teton / footprints 8064-8068 of 8354")
	)
	(layers
		(0 "F.Cu" signal "TOP")
		(4 "In1.Cu" signal "GND")
		(6 "In2.Cu" signal "IN1")
		(8 "In3.Cu" signal "GND1")
		(10 "In4.Cu" signal "IN2")
		(12 "In5.Cu" signal "GND2")
		(14 "In6.Cu" signal "IN3")
		(16 "In7.Cu" signal "GND3")
		(18 "In8.Cu" signal "VCC")
		(20 "In9.Cu" signal "VCC1")
		(22 "In10.Cu" signal "GND4")
		(24 "In11.Cu" signal "IN4")
		(26 "In12.Cu" signal "GND5")
		(28 "In13.Cu" signal "IN5")
		(30 "In14.Cu" signal "GND6")
		(32 "In15.Cu" signal "IN6")
		(34 "In16.Cu" signal "GND7")
		(2 "B.Cu" signal "BOTTOM")
		(9 "F.Adhes" user "F.Adhesive")
		(11 "B.Adhes" user "B.Adhesive")
		(13 "F.Paste" user "Package Geometry/Pastemask Top")
		(15 "B.Paste" user "Package Geometry/Pastemask Bottom")
		(5 "F.SilkS" user "Ref Des/Silkscreen Top")
		(7 "B.SilkS" user "Ref Des/Silkscreen Bottom")
		(1 "F.Mask" user "Board Geometry/Soldermask Top")
		(3 "B.Mask" user "Board Geometry/Soldermask Bottom")
		(17 "Dwgs.User" user "User.Drawings")
		(19 "Cmts.User" user "User.Comments")
		(21 "Eco1.User" user "User.Eco1")
		(23 "Eco2.User" user "User.Eco2")
		(25 "Edge.Cuts" user "Board Geometry/Outline")
		(27 "Margin" user)
		(31 "F.CrtYd" user "Package Geometry/Place Bound Top")
		(29 "B.CrtYd" user "Package Geometry/Place Bound Bottom")
		(35 "F.Fab" user "Ref Des/Assembly Top")
		(33 "B.Fab" user "Ref Des/Assembly Bottom")
	)
	(footprint ""
		(layer "B.Cu")
		(at 172.593 -100.294948 -90)
		(property "Reference" "R6020"
			(at 0 0 90)
			(layer "B.SilkS")
			(hide yes)
			(effects
				(font
					(size 1.27 1.27)
				)
				(justify mirror)
			)
		)
		(property "Value" ""
			(at 0 0 90)
			(layer "B.Fab")
			(effects
				(font
					(size 1.27 1.27)
				)
				(justify mirror)
			)
		)
		(duplicate_pad_numbers_are_jumpers no)
		(fp_line
			(start -0.7874 0.4064)
			(end 0.7874 0.4064)
			(stroke
				(width 0.1524)
				(type default)
			)
			(layer "B.SilkS")
		)
		(fp_line
			(start 0.7874 0.4064)
			(end 0.7874 -0.4064)
			(stroke
				(width 0.1524)
				(type default)
			)
			(layer "B.SilkS")
		)
		(fp_line
			(start -0.7874 -0.4064)
			(end -0.7874 0.4064)
			(stroke
				(width 0.1524)
				(type default)
			)
			(layer "B.SilkS")
		)
		(fp_line
			(start 0.7874 -0.4064)
			(end -0.7874 -0.4064)
			(stroke
				(width 0.1524)
				(type default)
			)
			(layer "B.SilkS")
		)
		(fp_line
			(start -0.67945 0.3048)
			(end -0.120396 0.3048)
			(stroke
				(width 0.1)
				(type default)
			)
			(layer "B.Fab")
		)
		(fp_line
			(start -0.120396 0.3048)
			(end -0.120396 0.2794)
			(stroke
				(width 0.1)
				(type default)
			)
			(layer "B.Fab")
		)
		(fp_line
			(start 0.12065 0.3048)
			(end 0.67945 0.3048)
			(stroke
				(width 0.1)
				(type default)
			)
			(layer "B.Fab")
		)
		(fp_line
			(start 0.67945 0.3048)
			(end 0.67945 -0.305054)
			(stroke
				(width 0.1)
				(type default)
			)
			(layer "B.Fab")
		)
		(fp_line
			(start -0.120396 0.2794)
			(end 0.12065 0.2794)
			(stroke
				(width 0.1)
				(type default)
			)
			(layer "B.Fab")
		)
		(fp_line
			(start 0.12065 0.2794)
			(end 0.12065 0.3048)
			(stroke
				(width 0.1)
				(type default)
			)
			(layer "B.Fab")
		)
		(fp_line
			(start -0.12065 -0.2794)
			(end -0.12065 -0.3048)
			(stroke
				(width 0.1)
				(type default)
			)
			(layer "B.Fab")
		)
		(fp_line
			(start 0.12065 -0.2794)
			(end -0.12065 -0.2794)
			(stroke
				(width 0.1)
				(type default)
			)
			(layer "B.Fab")
		)
		(fp_line
			(start -0.67945 -0.3048)
			(end -0.67945 0.3048)
			(stroke
				(width 0.1)
				(type default)
			)
			(layer "B.Fab")
		)
		(fp_line
			(start -0.12065 -0.3048)
			(end -0.67945 -0.3048)
			(stroke
				(width 0.1)
				(type default)
			)
			(layer "B.Fab")
		)
		(fp_line
			(start 0.12065 -0.305054)
			(end 0.12065 -0.2794)
			(stroke
				(width 0.1)
				(type default)
			)
			(layer "B.Fab")
		)
		(fp_line
			(start 0.67945 -0.305054)
			(end 0.12065 -0.305054)
			(stroke
				(width 0.1)
				(type default)
			)
			(layer "B.Fab")
		)
		(pad "1" smd circle
			(at 0.40005 0 90)
			(size 0 0)
			(layers "B.Cu" "B.Mask" "B.Paste")
			(net "P3V3_AUX")
		)
		(pad "2" smd circle
			(at -0.40005 0 90)
			(size 0 0)
			(layers "B.Cu" "B.Mask" "B.Paste")
			(net "SGPIO_SCM_DO_<1>")
		)
	)
	(footprint ""
		(layer "B.Cu")
		(at 402.186394 -354.439728 -90)
		(property "Reference" "R6128"
			(at 0 0 90)
			(layer "B.SilkS")
			(hide yes)
			(effects
				(font
					(size 1.27 1.27)
				)
				(justify mirror)
			)
		)
		(property "Value" ""
			(at 0 0 90)
			(layer "B.Fab")
			(effects
				(font
					(size 1.27 1.27)
				)
				(justify mirror)
			)
		)
		(duplicate_pad_numbers_are_jumpers no)
		(fp_line
			(start -0.7874 0.4064)
			(end 0.7874 0.4064)
			(stroke
				(width 0.1524)
				(type default)
			)
			(layer "B.SilkS")
		)
		(fp_line
			(start 0.7874 0.4064)
			(end 0.7874 -0.4064)
			(stroke
				(width 0.1524)
				(type default)
			)
			(layer "B.SilkS")
		)
		(fp_line
			(start -0.7874 -0.4064)
			(end -0.7874 0.4064)
			(stroke
				(width 0.1524)
				(type default)
			)
			(layer "B.SilkS")
		)
		(fp_line
			(start 0.7874 -0.4064)
			(end -0.7874 -0.4064)
			(stroke
				(width 0.1524)
				(type default)
			)
			(layer "B.SilkS")
		)
		(fp_line
			(start -0.67945 0.3048)
			(end -0.120396 0.3048)
			(stroke
				(width 0.1)
				(type default)
			)
			(layer "B.Fab")
		)
		(fp_line
			(start -0.120396 0.3048)
			(end -0.120396 0.2794)
			(stroke
				(width 0.1)
				(type default)
			)
			(layer "B.Fab")
		)
		(fp_line
			(start 0.12065 0.3048)
			(end 0.67945 0.3048)
			(stroke
				(width 0.1)
				(type default)
			)
			(layer "B.Fab")
		)
		(fp_line
			(start 0.67945 0.3048)
			(end 0.67945 -0.305054)
			(stroke
				(width 0.1)
				(type default)
			)
			(layer "B.Fab")
		)
		(fp_line
			(start -0.120396 0.2794)
			(end 0.12065 0.2794)
			(stroke
				(width 0.1)
				(type default)
			)
			(layer "B.Fab")
		)
		(fp_line
			(start 0.12065 0.2794)
			(end 0.12065 0.3048)
			(stroke
				(width 0.1)
				(type default)
			)
			(layer "B.Fab")
		)
		(fp_line
			(start -0.12065 -0.2794)
			(end -0.12065 -0.3048)
			(stroke
				(width 0.1)
				(type default)
			)
			(layer "B.Fab")
		)
		(fp_line
			(start 0.12065 -0.2794)
			(end -0.12065 -0.2794)
			(stroke
				(width 0.1)
				(type default)
			)
			(layer "B.Fab")
		)
		(fp_line
			(start -0.67945 -0.3048)
			(end -0.67945 0.3048)
			(stroke
				(width 0.1)
				(type default)
			)
			(layer "B.Fab")
		)
		(fp_line
			(start -0.12065 -0.3048)
			(end -0.67945 -0.3048)
			(stroke
				(width 0.1)
				(type default)
			)
			(layer "B.Fab")
		)
		(fp_line
			(start 0.12065 -0.305054)
			(end 0.12065 -0.2794)
			(stroke
				(width 0.1)
				(type default)
			)
			(layer "B.Fab")
		)
		(fp_line
			(start 0.67945 -0.305054)
			(end 0.12065 -0.305054)
			(stroke
				(width 0.1)
				(type default)
			)
			(layer "B.Fab")
		)
		(pad "1" smd circle
			(at 0.40005 0 90)
			(size 0 0)
			(layers "B.Cu" "B.Mask" "B.Paste")
			(net "FM_BOARD_SKU_ID1")
		)
		(pad "2" smd circle
			(at -0.40005 0 90)
			(size 0 0)
			(layers "B.Cu" "B.Mask" "B.Paste")
			(net "GND")
		)
	)
	(footprint ""
		(layer "B.Cu")
		(at 487.620564 -306.87264 90)
		(property "Reference" "X9028"
			(at 4.62026 -1.55829 90)
			(unlocked yes)
			(layer "B.SilkS")
			(effects
				(font
					(size 0.7874 0.5842)
					(thickness 0.1524)
				)
				(justify left mirror)
			)
		)
		(property "Value" ""
			(at 0 0 90)
			(layer "B.Fab")
			(effects
				(font
					(size 1.27 1.27)
				)
				(justify mirror)
			)
		)
		(property "User Part Number" "N_A"
			(at -1.30175 1.27 0)
			(unlocked yes)
			(layer "Cmts.User")
			(hide yes)
			(effects
				(font
					(size 0.635 0.4064)
					(thickness 0.1524)
				)
				(justify mirror)
			)
		)
		(property "Device Type" "TP_TDR_4P_FTS_TH-TP_TDR_4P_DIP,EMPTY,TP15"
			(at -1.30175 1.27 0)
			(unlocked yes)
			(layer "B.Fab")
			(hide yes)
			(effects
				(font
					(size 0.635 0.4064)
					(thickness 0.1524)
				)
				(justify mirror)
			)
		)
		(duplicate_pad_numbers_are_jumpers no)
		(fp_line
			(start 0 -1.27)
			(end 0 -0.635)
			(stroke
				(width 0.1524)
				(type default)
			)
			(layer "B.SilkS")
		)
		(fp_line
			(start -2.54 -1.27)
			(end 0 -1.27)
			(stroke
				(width 0.1524)
				(type default)
			)
			(layer "B.SilkS")
		)
		(fp_line
			(start -2.54 -1.1303)
			(end -2.54 -1.27)
			(stroke
				(width 0.1524)
				(type default)
			)
			(layer "B.SilkS")
		)
		(fp_line
			(start 0 0.635)
			(end 0 1.905)
			(stroke
				(width 0.1524)
				(type default)
			)
			(layer "B.SilkS")
		)
		(fp_line
			(start -2.54 1.4097)
			(end -2.54 1.1303)
			(stroke
				(width 0.1524)
				(type default)
			)
			(layer "B.SilkS")
		)
		(fp_line
			(start 0 3.175)
			(end 0 3.81)
			(stroke
				(width 0.1524)
				(type default)
			)
			(layer "B.SilkS")
		)
		(fp_line
			(start 0 3.81)
			(end -2.54 3.81)
			(stroke
				(width 0.1524)
				(type default)
			)
			(layer "B.SilkS")
		)
		(fp_line
			(start -2.54 3.81)
			(end -2.54 3.6703)
			(stroke
				(width 0.1524)
				(type default)
			)
			(layer "B.SilkS")
		)
		(fp_poly
			(pts
				(xy 0.761746 0) (xy 2.285746 -0.762) (xy 2.285746 0.762)
			)
			(stroke
				(width 0)
				(type default)
			)
			(fill yes)
			(layer "B.SilkS")
		)
		(fp_line
			(start 0 -1.27)
			(end 0 3.81)
			(stroke
				(width 0.1)
				(type default)
			)
			(layer "B.Fab")
		)
		(fp_line
			(start -2.54 -1.27)
			(end 0 -1.27)
			(stroke
				(width 0.1)
				(type default)
			)
			(layer "B.Fab")
		)
		(fp_line
			(start 0 3.81)
			(end -2.54 3.81)
			(stroke
				(width 0.1)
				(type default)
			)
			(layer "B.Fab")
		)
		(fp_line
			(start -2.54 3.81)
			(end -2.54 -1.27)
			(stroke
				(width 0.1)
				(type default)
			)
			(layer "B.Fab")
		)
		(fp_poly
			(pts
				(xy 0.761746 0) (xy 2.285746 -0.762) (xy 2.285746 0.762)
			)
			(stroke
				(width 0)
				(type default)
			)
			(fill yes)
			(layer "B.Fab")
		)
		(pad "1" thru_hole circle
			(at 0 0 270)
			(size 1.0033 1.0033)
			(drill 0.249936)
			(layers "*.Cu" "*.Mask")
			(remove_unused_layers no)
			(net "TDR_DIFF_85_NECK_IN6_DN")
			(clearance 0.10795)
			(padstack
				(mode front_inner_back)
				(layer "Inner"
					(shape circle)
					(size 0.8001 0.8001)
					(clearance 0.1524)
				)
				(layer "B.Cu"
					(shape circle)
					(size 1.0033 1.0033)
					(thermal_gap 0.10795)
					(clearance 0.10795)
				)
			)
		)
		(pad "2" thru_hole circle
			(at -2.54 0 270)
			(size 1.9939 1.9939)
			(drill 0.249936)
			(layers "*.Cu" "*.Mask")
			(remove_unused_layers no)
			(net "T1_GND")
			(clearance 0.10795)
			(padstack
				(mode front_inner_back)
				(layer "Inner"
					(shape circle)
					(size 0.8001 0.8001)
					(clearance 0.1524)
				)
				(layer "B.Cu"
					(shape circle)
					(size 1.9939 1.9939)
					(thermal_gap 0.10795)
					(clearance 0.10795)
				)
			)
		)
		(pad "3" thru_hole circle
			(at -2.54 2.54 270)
			(size 1.9939 1.9939)
			(drill 0.249936)
			(layers "*.Cu" "*.Mask")
			(remove_unused_layers no)
			(net "T1_GND")
			(clearance 0.10795)
			(padstack
				(mode front_inner_back)
				(layer "Inner"
					(shape circle)
					(size 0.8001 0.8001)
					(clearance 0.1524)
				)
				(layer "B.Cu"
					(shape circle)
					(size 1.9939 1.9939)
					(thermal_gap 0.10795)
					(clearance 0.10795)
				)
			)
		)
		(pad "4" thru_hole circle
			(at 0 2.54 270)
			(size 1.0033 1.0033)
			(drill 0.249936)
			(layers "*.Cu" "*.Mask")
			(remove_unused_layers no)
			(net "TDR_DIFF_85_NECK_IN6_DP")
			(clearance 0.10795)
			(padstack
				(mode front_inner_back)
				(layer "Inner"
					(shape circle)
					(size 0.8001 0.8001)
					(clearance 0.1524)
				)
				(layer "B.Cu"
					(shape circle)
					(size 1.0033 1.0033)
					(thermal_gap 0.10795)
					(clearance 0.10795)
				)
			)
		)
	)
	(footprint ""
		(layer "B.Cu")
		(at 165.599618 -417.962588)
		(property "Reference" "R4120"
			(at 0 0 0)
			(layer "B.SilkS")
			(hide yes)
			(effects
				(font
					(size 1.27 1.27)
				)
				(justify mirror)
			)
		)
		(property "Value" ""
			(at 0 0 0)
			(layer "B.Fab")
			(effects
				(font
					(size 1.27 1.27)
				)
				(justify mirror)
			)
		)
		(duplicate_pad_numbers_are_jumpers no)
		(fp_line
			(start -0.7874 -0.4064)
			(end -0.7874 0.4064)
			(stroke
				(width 0.1524)
				(type default)
			)
			(layer "B.SilkS")
		)
		(fp_line
			(start -0.7874 0.4064)
			(end 0.7874 0.4064)
			(stroke
				(width 0.1524)
				(type default)
			)
			(layer "B.SilkS")
		)
		(fp_line
			(start 0.7874 -0.4064)
			(end -0.7874 -0.4064)
			(stroke
				(width 0.1524)
				(type default)
			)
			(layer "B.SilkS")
		)
		(fp_line
			(start 0.7874 0.4064)
			(end 0.7874 -0.4064)
			(stroke
				(width 0.1524)
				(type default)
			)
			(layer "B.SilkS")
		)
		(fp_line
			(start -0.67945 -0.3048)
			(end -0.67945 0.3048)
			(stroke
				(width 0.1)
				(type default)
			)
			(layer "B.Fab")
		)
		(fp_line
			(start -0.67945 0.3048)
			(end -0.120396 0.3048)
			(stroke
				(width 0.1)
				(type default)
			)
			(layer "B.Fab")
		)
		(fp_line
			(start -0.12065 -0.3048)
			(end -0.67945 -0.3048)
			(stroke
				(width 0.1)
				(type default)
			)
			(layer "B.Fab")
		)
		(fp_line
			(start -0.12065 -0.2794)
			(end -0.12065 -0.3048)
			(stroke
				(width 0.1)
				(type default)
			)
			(layer "B.Fab")
		)
		(fp_line
			(start -0.120396 0.2794)
			(end 0.12065 0.2794)
			(stroke
				(width 0.1)
				(type default)
			)
			(layer "B.Fab")
		)
		(fp_line
			(start -0.120396 0.3048)
			(end -0.120396 0.2794)
			(stroke
				(width 0.1)
				(type default)
			)
			(layer "B.Fab")
		)
		(fp_line
			(start 0.12065 -0.305054)
			(end 0.12065 -0.2794)
			(stroke
				(width 0.1)
				(type default)
			)
			(layer "B.Fab")
		)
		(fp_line
			(start 0.12065 -0.2794)
			(end -0.12065 -0.2794)
			(stroke
				(width 0.1)
				(type default)
			)
			(layer "B.Fab")
		)
		(fp_line
			(start 0.12065 0.2794)
			(end 0.12065 0.3048)
			(stroke
				(width 0.1)
				(type default)
			)
			(layer "B.Fab")
		)
		(fp_line
			(start 0.12065 0.3048)
			(end 0.67945 0.3048)
			(stroke
				(width 0.1)
				(type default)
			)
			(layer "B.Fab")
		)
		(fp_line
			(start 0.67945 -0.305054)
			(end 0.12065 -0.305054)
			(stroke
				(width 0.1)
				(type default)
			)
			(layer "B.Fab")
		)
		(fp_line
			(start 0.67945 0.3048)
			(end 0.67945 -0.305054)
			(stroke
				(width 0.1)
				(type default)
			)
			(layer "B.Fab")
		)
		(pad "1" smd circle
			(at 0.40005 0 180)
			(size 0 0)
			(layers "B.Cu" "B.Mask" "B.Paste")
			(net "GPU_3V3IO_RSVD0_FFU")
		)
		(pad "2" smd circle
			(at -0.40005 0 180)
			(size 0 0)
			(layers "B.Cu" "B.Mask" "B.Paste")
			(net "GND")
		)
	)
	(footprint ""
		(layer "B.Cu")
		(at 206.22133 -195.95211)
		(property "Reference" "R1711"
			(at 0 0 0)
			(layer "B.SilkS")
			(hide yes)
			(effects
				(font
					(size 1.27 1.27)
				)
				(justify mirror)
			)
		)
		(property "Value" ""
			(at 0 0 0)
			(layer "B.Fab")
			(effects
				(font
					(size 1.27 1.27)
				)
				(justify mirror)
			)
		)
		(duplicate_pad_numbers_are_jumpers no)
		(fp_line
			(start -0.7874 -0.4064)
			(end -0.7874 0.4064)
			(stroke
				(width 0.1524)
				(type default)
			)
			(layer "B.SilkS")
		)
		(fp_line
			(start -0.7874 0.4064)
			(end 0.7874 0.4064)
			(stroke
				(width 0.1524)
				(type default)
			)
			(layer "B.SilkS")
		)
		(fp_line
			(start 0.7874 -0.4064)
			(end -0.7874 -0.4064)
			(stroke
				(width 0.1524)
				(type default)
			)
			(layer "B.SilkS")
		)
		(fp_line
			(start 0.7874 0.4064)
			(end 0.7874 -0.4064)
			(stroke
				(width 0.1524)
				(type default)
			)
			(layer "B.SilkS")
		)
		(fp_line
			(start -0.67945 -0.3048)
			(end -0.67945 0.3048)
			(stroke
				(width 0.1)
				(type default)
			)
			(layer "B.Fab")
		)
		(fp_line
			(start -0.67945 0.3048)
			(end -0.120396 0.3048)
			(stroke
				(width 0.1)
				(type default)
			)
			(layer "B.Fab")
		)
		(fp_line
			(start -0.12065 -0.3048)
			(end -0.67945 -0.3048)
			(stroke
				(width 0.1)
				(type default)
			)
			(layer "B.Fab")
		)
		(fp_line
			(start -0.12065 -0.2794)
			(end -0.12065 -0.3048)
			(stroke
				(width 0.1)
				(type default)
			)
			(layer "B.Fab")
		)
		(fp_line
			(start -0.120396 0.2794)
			(end 0.12065 0.2794)
			(stroke
				(width 0.1)
				(type default)
			)
			(layer "B.Fab")
		)
		(fp_line
			(start -0.120396 0.3048)
			(end -0.120396 0.2794)
			(stroke
				(width 0.1)
				(type default)
			)
			(layer "B.Fab")
		)
		(fp_line
			(start 0.12065 -0.305054)
			(end 0.12065 -0.2794)
			(stroke
				(width 0.1)
				(type default)
			)
			(layer "B.Fab")
		)
		(fp_line
			(start 0.12065 -0.2794)
			(end -0.12065 -0.2794)
			(stroke
				(width 0.1)
				(type default)
			)
			(layer "B.Fab")
		)
		(fp_line
			(start 0.12065 0.2794)
			(end 0.12065 0.3048)
			(stroke
				(width 0.1)
				(type default)
			)
			(layer "B.Fab")
		)
		(fp_line
			(start 0.12065 0.3048)
			(end 0.67945 0.3048)
			(stroke
				(width 0.1)
				(type default)
			)
			(layer "B.Fab")
		)
		(fp_line
			(start 0.67945 -0.305054)
			(end 0.12065 -0.305054)
			(stroke
				(width 0.1)
				(type default)
			)
			(layer "B.Fab")
		)
		(fp_line
			(start 0.67945 0.3048)
			(end 0.67945 -0.305054)
			(stroke
				(width 0.1)
				(type default)
			)
			(layer "B.Fab")
		)
		(pad "1" smd circle
			(at 0.40005 0 180)
			(size 0 0)
			(layers "B.Cu" "B.Mask" "B.Paste")
			(net "I3C_SPD_DDRGL_CPU1_SDA")
		)
		(pad "2" smd circle
			(at -0.40005 0 180)
			(size 0 0)
			(layers "B.Cu" "B.Mask" "B.Paste")
			(net "I3C_SPD_DDRL_CPU1_SDA")
		)
	)
)
